(kicad_pcb
	(version 20260206)
	(generator "pcbnew")
	(generator_version "10.0")
	(general
		(thickness 1.6)
		(legacy_teardrops no)
	)
	(paper "A4")
	(title_block
		(title "01162023_DA0F0TEBIF0_F0T_Expander_BD_F_brd_V02_OCP.brd")
		(comment 1 "Grand Teton / footprints 2560-2565 of 9728")
	)
	(layers
		(0 "F.Cu" signal "TOP")
		(4 "In1.Cu" signal "GND")
		(6 "In2.Cu" signal "VCC")
		(8 "In3.Cu" signal "VCC1")
		(10 "In4.Cu" signal "GND1")
		(12 "In5.Cu" signal "IN1")
		(14 "In6.Cu" signal "GND2")
		(16 "In7.Cu" signal "IN2")
		(18 "In8.Cu" signal "GND3")
		(20 "In9.Cu" signal "IN3")
		(22 "In10.Cu" signal "GND4")
		(24 "In11.Cu" signal "IN4")
		(26 "In12.Cu" signal "GND5")
		(28 "In13.Cu" signal "IN5")
		(30 "In14.Cu" signal "GND6")
		(32 "In15.Cu" signal "IN6")
		(34 "In16.Cu" signal "GND7")
		(2 "B.Cu" signal "BOTTOM")
		(9 "F.Adhes" user "F.Adhesive")
		(11 "B.Adhes" user "B.Adhesive")
		(13 "F.Paste" user "Package Geometry/Pastemask Top")
		(15 "B.Paste" user "Package Geometry/Pastemask Bottom")
		(5 "F.SilkS" user "Ref Des/Silkscreen Top")
		(7 "B.SilkS" user "Ref Des/Silkscreen Bottom")
		(1 "F.Mask" user "Board Geometry/Soldermask Top")
		(3 "B.Mask" user "Board Geometry/Soldermask Bottom")
		(17 "Dwgs.User" user "User.Drawings")
		(19 "Cmts.User" user "User.Comments")
		(21 "Eco1.User" user "User.Eco1")
		(23 "Eco2.User" user "User.Eco2")
		(25 "Edge.Cuts" user "Board Geometry/Outline")
		(27 "Margin" user)
		(31 "F.CrtYd" user "Package Geometry/Place Bound Top")
		(29 "B.CrtYd" user "Package Geometry/Place Bound Bottom")
		(35 "F.Fab" user "Ref Des/Assembly Top")
		(33 "B.Fab" user "Ref Des/Assembly Bottom")
	)
	(footprint ""
		(layer "F.Cu")
		(at 124.796296 -169.484802 -90)
		(property "Reference" "U438"
			(at -1.35001 1.893824 90)
			(unlocked yes)
			(layer "F.SilkS")
			(effects
				(font
					(size 0.7874 0.5842)
					(thickness 0.1524)
				)
			)
		)
		(property "Value" ""
			(at 0 0 270)
			(layer "F.Fab")
			(effects
				(font
					(size 1.27 1.27)
				)
			)
		)
		(duplicate_pad_numbers_are_jumpers no)
		(fp_line
			(start -1.7272 1.1176)
			(end -1.7272 -1.1176)
			(stroke
				(width 0.1524)
				(type default)
			)
			(layer "F.SilkS")
		)
		(fp_line
			(start 1.7272 1.1176)
			(end -1.7272 1.1176)
			(stroke
				(width 0.1524)
				(type default)
			)
			(layer "F.SilkS")
		)
		(fp_line
			(start 0 -0.7366)
			(end -0.254 -1.1176)
			(stroke
				(width 0.1524)
				(type default)
			)
			(layer "F.SilkS")
		)
		(fp_line
			(start -0.254 -1.1176)
			(end -1.7272 -1.1176)
			(stroke
				(width 0.1524)
				(type default)
			)
			(layer "F.SilkS")
		)
		(fp_line
			(start 0.254 -1.1176)
			(end 0 -0.7366)
			(stroke
				(width 0.1524)
				(type default)
			)
			(layer "F.SilkS")
		)
		(fp_line
			(start 1.7272 -1.1176)
			(end 1.7272 1.1176)
			(stroke
				(width 0.1524)
				(type default)
			)
			(layer "F.SilkS")
		)
		(fp_line
			(start 1.7272 -1.1176)
			(end 0.254 -1.1176)
			(stroke
				(width 0.1524)
				(type default)
			)
			(layer "F.SilkS")
		)
		(fp_poly
			(pts
				(xy -1.14173 -1.37922) (xy -1.52273 -2.14122) (xy -0.76073 -2.14122)
			)
			(stroke
				(width 0)
				(type default)
			)
			(fill yes)
			(layer "F.SilkS")
		)
		(fp_line
			(start -1.5748 1.1176)
			(end 1.5748 1.1176)
			(stroke
				(width 0.1)
				(type default)
			)
			(layer "F.Fab")
		)
		(fp_line
			(start 1.5748 1.1176)
			(end 1.5748 -1.1176)
			(stroke
				(width 0.1)
				(type default)
			)
			(layer "F.Fab")
		)
		(fp_line
			(start -1.5748 -1.1176)
			(end -1.5748 1.1176)
			(stroke
				(width 0.1)
				(type default)
			)
			(layer "F.Fab")
		)
		(fp_line
			(start 1.5748 -1.1176)
			(end -1.5748 -1.1176)
			(stroke
				(width 0.1)
				(type default)
			)
			(layer "F.Fab")
		)
		(fp_poly
			(pts
				(xy -1.9558 -0.649986) (xy -2.7178 -0.268986) (xy -2.7178 -1.030986)
			)
			(stroke
				(width 0)
				(type default)
			)
			(fill yes)
			(layer "F.Fab")
		)
		(pad "1" smd rect
			(at -0.999998 -0.649986 180)
			(size 0.3556 1.1176)
			(layers "F.Cu" "F.Mask" "F.Paste")
			(net "NIC0_CLK_EN_R_N")
		)
		(pad "2" smd rect
			(at -0.999998 0 180)
			(size 0.3556 1.1176)
			(layers "F.Cu" "F.Mask" "F.Paste")
			(net "GND")
		)
		(pad "3" smd rect
			(at -0.999998 0.649986 180)
			(size 0.3556 1.1176)
			(layers "F.Cu" "F.Mask" "F.Paste")
			(net "NIC1_CLK_EN_R_N")
		)
		(pad "4" smd rect
			(at 0.999998 0.649986 180)
			(size 0.3556 1.1176)
			(layers "F.Cu" "F.Mask" "F.Paste")
			(net "NIC1_CLK_EN_BUF_N")
		)
		(pad "5" smd rect
			(at 0.999998 0 180)
			(size 0.3556 1.1176)
			(layers "F.Cu" "F.Mask" "F.Paste")
			(net "P3V3_AUX")
		)
		(pad "6" smd rect
			(at 0.999998 -0.649986 180)
			(size 0.3556 1.1176)
			(layers "F.Cu" "F.Mask" "F.Paste")
			(net "NIC0_CLK_EN_BUF_N")
		)
	)
	(footprint ""
		(layer "F.Cu")
		(at 199.394064 -35.264852)
		(property "Reference" "R5676"
			(at 0 0 0)
			(layer "F.SilkS")
			(hide yes)
			(effects
				(font
					(size 1.27 1.27)
				)
			)
		)
		(property "Value" ""
			(at 0 0 0)
			(layer "F.Fab")
			(effects
				(font
					(size 1.27 1.27)
				)
			)
		)
		(duplicate_pad_numbers_are_jumpers no)
		(fp_line
			(start -0.7874 -0.4064)
			(end 0.7874 -0.4064)
			(stroke
				(width 0.1524)
				(type default)
			)
			(layer "F.SilkS")
		)
		(fp_line
			(start -0.7874 0.4064)
			(end -0.7874 -0.4064)
			(stroke
				(width 0.1524)
				(type default)
			)
			(layer "F.SilkS")
		)
		(fp_line
			(start 0.7874 -0.4064)
			(end 0.7874 0.4064)
			(stroke
				(width 0.1524)
				(type default)
			)
			(layer "F.SilkS")
		)
		(fp_line
			(start 0.7874 0.4064)
			(end -0.7874 0.4064)
			(stroke
				(width 0.1524)
				(type default)
			)
			(layer "F.SilkS")
		)
		(fp_line
			(start -0.67945 -0.305054)
			(end -0.12065 -0.305054)
			(stroke
				(width 0.1)
				(type default)
			)
			(layer "F.Fab")
		)
		(fp_line
			(start -0.67945 0.3048)
			(end -0.67945 -0.305054)
			(stroke
				(width 0.1)
				(type default)
			)
			(layer "F.Fab")
		)
		(fp_line
			(start -0.12065 -0.305054)
			(end -0.12065 -0.2794)
			(stroke
				(width 0.1)
				(type default)
			)
			(layer "F.Fab")
		)
		(fp_line
			(start -0.12065 -0.2794)
			(end 0.12065 -0.2794)
			(stroke
				(width 0.1)
				(type default)
			)
			(layer "F.Fab")
		)
		(fp_line
			(start -0.12065 0.2794)
			(end -0.12065 0.3048)
			(stroke
				(width 0.1)
				(type default)
			)
			(layer "F.Fab")
		)
		(fp_line
			(start -0.12065 0.3048)
			(end -0.67945 0.3048)
			(stroke
				(width 0.1)
				(type default)
			)
			(layer "F.Fab")
		)
		(fp_line
			(start 0.120396 0.2794)
			(end -0.12065 0.2794)
			(stroke
				(width 0.1)
				(type default)
			)
			(layer "F.Fab")
		)
		(fp_line
			(start 0.120396 0.3048)
			(end 0.120396 0.2794)
			(stroke
				(width 0.1)
				(type default)
			)
			(layer "F.Fab")
		)
		(fp_line
			(start 0.12065 -0.3048)
			(end 0.67945 -0.3048)
			(stroke
				(width 0.1)
				(type default)
			)
			(layer "F.Fab")
		)
		(fp_line
			(start 0.12065 -0.2794)
			(end 0.12065 -0.3048)
			(stroke
				(width 0.1)
				(type default)
			)
			(layer "F.Fab")
		)
		(fp_line
			(start 0.67945 -0.3048)
			(end 0.67945 0.3048)
			(stroke
				(width 0.1)
				(type default)
			)
			(layer "F.Fab")
		)
		(fp_line
			(start 0.67945 0.3048)
			(end 0.120396 0.3048)
			(stroke
				(width 0.1)
				(type default)
			)
			(layer "F.Fab")
		)
		(pad "1" smd circle
			(at -0.40005 0)
			(size 0 0)
			(layers "F.Cu" "F.Mask" "F.Paste")
			(net "RST_SMB_SSD7_ISO_N")
		)
		(pad "2" smd circle
			(at 0.40005 0)
			(size 0 0)
			(layers "F.Cu" "F.Mask" "F.Paste")
			(net "GND")
		)
	)
	(footprint ""
		(layer "F.Cu")
		(at 378.2949 -350.098614 90)
		(property "Reference" "C785"
			(at 0 0 90)
			(layer "F.SilkS")
			(hide yes)
			(effects
				(font
					(size 1.27 1.27)
				)
			)
		)
		(property "Value" ""
			(at 0 0 90)
			(layer "F.Fab")
			(effects
				(font
					(size 1.27 1.27)
				)
			)
		)
		(duplicate_pad_numbers_are_jumpers no)
		(fp_line
			(start 0.299974 -0.150114)
			(end 0.299974 0.150114)
			(stroke
				(width 0.1)
				(type default)
			)
			(layer "F.Fab")
		)
		(fp_line
			(start -0.299974 -0.150114)
			(end 0.299974 -0.150114)
			(stroke
				(width 0.1)
				(type default)
			)
			(layer "F.Fab")
		)
		(fp_line
			(start 0.299974 0.150114)
			(end -0.299974 0.150114)
			(stroke
				(width 0.1)
				(type default)
			)
			(layer "F.Fab")
		)
		(fp_line
			(start -0.299974 0.150114)
			(end -0.299974 -0.150114)
			(stroke
				(width 0.1)
				(type default)
			)
			(layer "F.Fab")
		)
		(pad "1" smd rect
			(at -0.2667 0 90)
			(size 0.3048 0.381)
			(layers "F.Cu" "F.Mask" "F.Paste")
			(net "P5E_PEX3_STN6_TX_DN<100>")
		)
		(pad "2" smd rect
			(at 0.2667 0 90)
			(size 0.3048 0.381)
			(layers "F.Cu" "F.Mask" "F.Paste")
			(net "P5E_PEX3_STN6_TX_C_DN<100>")
		)
	)
	(footprint ""
		(layer "F.Cu")
		(at 336.042 -147.955 180)
		(property "Reference" "R4802"
			(at 0 0 180)
			(layer "F.SilkS")
			(hide yes)
			(effects
				(font
					(size 1.27 1.27)
				)
			)
		)
		(property "Value" ""
			(at 0 0 180)
			(layer "F.Fab")
			(effects
				(font
					(size 1.27 1.27)
				)
			)
		)
		(duplicate_pad_numbers_are_jumpers no)
		(fp_line
			(start 0.7874 0.4064)
			(end -0.7874 0.4064)
			(stroke
				(width 0.1524)
				(type default)
			)
			(layer "F.SilkS")
		)
		(fp_line
			(start 0.7874 -0.4064)
			(end 0.7874 0.4064)
			(stroke
				(width 0.1524)
				(type default)
			)
			(layer "F.SilkS")
		)
		(fp_line
			(start -0.7874 0.4064)
			(end -0.7874 -0.4064)
			(stroke
				(width 0.1524)
				(type default)
			)
			(layer "F.SilkS")
		)
		(fp_line
			(start -0.7874 -0.4064)
			(end 0.7874 -0.4064)
			(stroke
				(width 0.1524)
				(type default)
			)
			(layer "F.SilkS")
		)
		(fp_line
			(start 0.67945 0.3048)
			(end 0.120396 0.3048)
			(stroke
				(width 0.1)
				(type default)
			)
			(layer "F.Fab")
		)
		(fp_line
			(start 0.67945 -0.3048)
			(end 0.67945 0.3048)
			(stroke
				(width 0.1)
				(type default)
			)
			(layer "F.Fab")
		)
		(fp_line
			(start 0.12065 -0.2794)
			(end 0.12065 -0.3048)
			(stroke
				(width 0.1)
				(type default)
			)
			(layer "F.Fab")
		)
		(fp_line
			(start 0.12065 -0.3048)
			(end 0.67945 -0.3048)
			(stroke
				(width 0.1)
				(type default)
			)
			(layer "F.Fab")
		)
		(fp_line
			(start 0.120396 0.3048)
			(end 0.120396 0.2794)
			(stroke
				(width 0.1)
				(type default)
			)
			(layer "F.Fab")
		)
		(fp_line
			(start 0.120396 0.2794)
			(end -0.12065 0.2794)
			(stroke
				(width 0.1)
				(type default)
			)
			(layer "F.Fab")
		)
		(fp_line
			(start -0.12065 0.3048)
			(end -0.67945 0.3048)
			(stroke
				(width 0.1)
				(type default)
			)
			(layer "F.Fab")
		)
		(fp_line
			(start -0.12065 0.2794)
			(end -0.12065 0.3048)
			(stroke
				(width 0.1)
				(type default)
			)
			(layer "F.Fab")
		)
		(fp_line
			(start -0.12065 -0.2794)
			(end 0.12065 -0.2794)
			(stroke
				(width 0.1)
				(type default)
			)
			(layer "F.Fab")
		)
		(fp_line
			(start -0.12065 -0.305054)
			(end -0.12065 -0.2794)
			(stroke
				(width 0.1)
				(type default)
			)
			(layer "F.Fab")
		)
		(fp_line
			(start -0.67945 0.3048)
			(end -0.67945 -0.305054)
			(stroke
				(width 0.1)
				(type default)
			)
			(layer "F.Fab")
		)
		(fp_line
			(start -0.67945 -0.305054)
			(end -0.12065 -0.305054)
			(stroke
				(width 0.1)
				(type default)
			)
			(layer "F.Fab")
		)
		(pad "1" smd circle
			(at -0.40005 0 180)
			(size 0 0)
			(layers "F.Cu" "F.Mask" "F.Paste")
			(net "SSD14_PEX_PWR_EN_R")
		)
		(pad "2" smd circle
			(at 0.40005 0 180)
			(size 0 0)
			(layers "F.Cu" "F.Mask" "F.Paste")
			(net "GND")
		)
	)
	(footprint ""
		(layer "F.Cu")
		(at 283.539184 -177.428398 -90)
		(property "Reference" "Q5"
			(at 0.745998 -1.856486 90)
			(unlocked yes)
			(layer "F.SilkS")
			(effects
				(font
					(size 0.7874 0.5842)
					(thickness 0.1524)
				)
				(justify left)
			)
		)
		(property "Value" ""
			(at 0 0 270)
			(layer "F.Fab")
			(effects
				(font
					(size 1.27 1.27)
				)
			)
		)
		(duplicate_pad_numbers_are_jumpers no)
		(fp_line
			(start -1.38176 1.100074)
			(end 1.38176 1.100074)
			(stroke
				(width 0.1524)
				(type default)
			)
			(layer "F.SilkS")
		)
		(fp_line
			(start 1.38176 1.100074)
			(end 1.38176 -1.100074)
			(stroke
				(width 0.1524)
				(type default)
			)
			(layer "F.SilkS")
		)
		(fp_line
			(start 0 -0.508)
			(end -0.592074 -1.100074)
			(stroke
				(width 0.1524)
				(type default)
			)
			(layer "F.SilkS")
		)
		(fp_line
			(start -1.38176 -1.100074)
			(end -1.38176 1.100074)
			(stroke
				(width 0.1524)
				(type default)
			)
			(layer "F.SilkS")
		)
		(fp_line
			(start -0.592074 -1.100074)
			(end -1.38176 -1.100074)
			(stroke
				(width 0.1524)
				(type default)
			)
			(layer "F.SilkS")
		)
		(fp_line
			(start 0.592074 -1.100074)
			(end 0 -0.508)
			(stroke
				(width 0.1524)
				(type default)
			)
			(layer "F.SilkS")
		)
		(fp_line
			(start 1.38176 -1.100074)
			(end 0.592074 -1.100074)
			(stroke
				(width 0.1524)
				(type default)
			)
			(layer "F.SilkS")
		)
		(fp_poly
			(pts
				(xy -1.705864 -1.452118) (xy -1.549908 -0.984758) (xy -2.017268 -1.140714)
			)
			(stroke
				(width 0)
				(type default)
			)
			(fill yes)
			(layer "F.SilkS")
		)
		(fp_line
			(start -0.674878 1.100074)
			(end 0.674878 1.100074)
			(stroke
				(width 0.1)
				(type default)
			)
			(layer "F.Fab")
		)
		(fp_line
			(start 0.674878 1.100074)
			(end 0.674878 -1.100074)
			(stroke
				(width 0.1)
				(type default)
			)
			(layer "F.Fab")
		)
		(fp_line
			(start -0.674878 -1.100074)
			(end -0.674878 1.100074)
			(stroke
				(width 0.1)
				(type default)
			)
			(layer "F.Fab")
		)
		(fp_line
			(start 0.674878 -1.100074)
			(end -0.674878 -1.100074)
			(stroke
				(width 0.1)
				(type default)
			)
			(layer "F.Fab")
		)
		(fp_poly
			(pts
				(xy -1.9431 -0.870204) (xy -1.50241 -0.649986) (xy -1.9431 -0.429768)
			)
			(stroke
				(width 0)
				(type default)
			)
			(fill yes)
			(layer "F.Fab")
		)
		(pad "1" smd rect
			(at -0.94996 -0.649986 180)
			(size 0.4318 0.6096)
			(layers "F.Cu" "F.Mask" "F.Paste")
			(net "GND")
		)
		(pad "2" smd rect
			(at -0.94996 0 180)
			(size 0.4318 0.6096)
			(layers "F.Cu" "F.Mask" "F.Paste")
			(net "HP_NIC4_HSC_PWRGD_N")
		)
		(pad "3" smd rect
			(at -0.94996 0.649986 180)
			(size 0.4318 0.6096)
			(layers "F.Cu" "F.Mask" "F.Paste")
			(net "HP_NIC4_HSC_PWRGD_N")
		)
		(pad "4" smd rect
			(at 0.94996 0.649986 180)
			(size 0.4318 0.6096)
			(layers "F.Cu" "F.Mask" "F.Paste")
			(net "GND")
		)
		(pad "5" smd rect
			(at 0.94996 0 180)
			(size 0.4318 0.6096)
			(layers "F.Cu" "F.Mask" "F.Paste")
			(net "PWRGD_P12V_NIC4_R")
		)
		(pad "6" smd rect
			(at 0.94996 -0.649986 180)
			(size 0.4318 0.6096)
			(layers "F.Cu" "F.Mask" "F.Paste")
			(net "HP_NIC4_PWRGD_R")
		)
	)
	(footprint ""
		(layer "F.Cu")
		(at 135.89635 -47.20082 90)
		(property "Reference" "C310"
			(at 0 0 90)
			(layer "F.SilkS")
			(hide yes)
			(effects
				(font
					(size 1.27 1.27)
				)
			)
		)
		(property "Value" ""
			(at 0 0 90)
			(layer "F.Fab")
			(effects
				(font
					(size 1.27 1.27)
				)
			)
		)
		(duplicate_pad_numbers_are_jumpers no)
		(fp_line
			(start 0.7874 -0.4064)
			(end 0.7874 0.4064)
			(stroke
				(width 0.1524)
				(type default)
			)
			(layer "F.SilkS")
		)
		(fp_line
			(start -0.7874 -0.4064)
			(end 0.7874 -0.4064)
			(stroke
				(width 0.1524)
				(type default)
			)
			(layer "F.SilkS")
		)
		(fp_line
			(start 0.7874 0.4064)
			(end -0.7874 0.4064)
			(stroke
				(width 0.1524)
				(type default)
			)
			(layer "F.SilkS")
		)
		(fp_line
			(start -0.7874 0.4064)
			(end -0.7874 -0.4064)
			(stroke
				(width 0.1524)
				(type default)
			)
			(layer "F.SilkS")
		)
		(fp_line
			(start -0.12065 -0.305054)
			(end -0.12065 -0.2794)
			(stroke
				(width 0.1)
				(type default)
			)
			(layer "F.Fab")
		)
		(fp_line
			(start -0.67945 -0.305054)
			(end -0.12065 -0.305054)
			(stroke
				(width 0.1)
				(type default)
			)
			(layer "F.Fab")
		)
		(fp_line
			(start 0.67945 -0.3048)
			(end 0.67945 0.3048)
			(stroke
				(width 0.1)
				(type default)
			)
			(layer "F.Fab")
		)
		(fp_line
			(start 0.12065 -0.3048)
			(end 0.67945 -0.3048)
			(stroke
				(width 0.1)
				(type default)
			)
			(layer "F.Fab")
		)
		(fp_line
			(start 0.12065 -0.2794)
			(end 0.12065 -0.3048)
			(stroke
				(width 0.1)
				(type default)
			)
			(layer "F.Fab")
		)
		(fp_line
			(start -0.12065 -0.2794)
			(end 0.12065 -0.2794)
			(stroke
				(width 0.1)
				(type default)
			)
			(layer "F.Fab")
		)
		(fp_line
			(start 0.120396 0.2794)
			(end -0.12065 0.2794)
			(stroke
				(width 0.1)
				(type default)
			)
			(layer "F.Fab")
		)
		(fp_line
			(start -0.12065 0.2794)
			(end -0.12065 0.3048)
			(stroke
				(width 0.1)
				(type default)
			)
			(layer "F.Fab")
		)
		(fp_line
			(start 0.67945 0.3048)
			(end 0.120396 0.3048)
			(stroke
				(width 0.1)
				(type default)
			)
			(layer "F.Fab")
		)
		(fp_line
			(start 0.120396 0.3048)
			(end 0.120396 0.2794)
			(stroke
				(width 0.1)
				(type default)
			)
			(layer "F.Fab")
		)
		(fp_line
			(start -0.12065 0.3048)
			(end -0.67945 0.3048)
			(stroke
				(width 0.1)
				(type default)
			)
			(layer "F.Fab")
		)
		(fp_line
			(start -0.67945 0.3048)
			(end -0.67945 -0.305054)
			(stroke
				(width 0.1)
				(type default)
			)
			(layer "F.Fab")
		)
		(pad "1" smd circle
			(at -0.40005 0 90)
			(size 0 0)
			(layers "F.Cu" "F.Mask" "F.Paste")
			(net "P12V_SSD4_R")
		)
		(pad "2" smd circle
			(at 0.40005 0 90)
			(size 0 0)
			(layers "F.Cu" "F.Mask" "F.Paste")
			(net "GND")
		)
	)
)
